# T6G (Grand Teton) — schematic netlist excerpt (pin names and nets, part order shuffled) for the footprints in the layout excerpt that follows; sources: Cadence DE-HDL packaged netlist, KiCad conversion of 04192023_DAF0TMB3IC0_F0TG_MB_C_brd_V02_OCP.brd

R1292  Q_RES  10 1% CHIP  pkg 0402LF  page 357 : A = P12V_E1S_0_R ; B = VSENSE_P12V_INA230_8_INN
R19  Q_RES  10K 1% CHIP  pkg 0402LF  page 83 : A = RST_CPU1_PERST1_N ; B = GND

(kicad_pcb
	(version 20260206)
	(generator "pcbnew")
	(generator_version "10.0")
	(general
		(thickness 1.6)
		(legacy_teardrops no)
	)
	(paper "A4")
	(title_block
		(title "04192023_DAF0TMB3IC0_F0TG_MB_C_brd_V02_OCP.brd")
		(comment 1 "Grand Teton / footprints 3491-3492 of 8354")
	)
	(layers
		(0 "F.Cu" signal "TOP")
		(4 "In1.Cu" signal "GND")
		(6 "In2.Cu" signal "IN1")
		(8 "In3.Cu" signal "GND1")
		(10 "In4.Cu" signal "IN2")
		(12 "In5.Cu" signal "GND2")
		(14 "In6.Cu" signal "IN3")
		(16 "In7.Cu" signal "GND3")
		(18 "In8.Cu" signal "VCC")
		(20 "In9.Cu" signal "VCC1")
		(22 "In10.Cu" signal "GND4")
		(24 "In11.Cu" signal "IN4")
		(26 "In12.Cu" signal "GND5")
		(28 "In13.Cu" signal "IN5")
		(30 "In14.Cu" signal "GND6")
		(32 "In15.Cu" signal "IN6")
		(34 "In16.Cu" signal "GND7")
		(2 "B.Cu" signal "BOTTOM")
		(9 "F.Adhes" user "F.Adhesive")
		(11 "B.Adhes" user "B.Adhesive")
		(13 "F.Paste" user "Package Geometry/Pastemask Top")
		(15 "B.Paste" user "Package Geometry/Pastemask Bottom")
		(5 "F.SilkS" user "Ref Des/Silkscreen Top")
		(7 "B.SilkS" user "Ref Des/Silkscreen Bottom")
		(1 "F.Mask" user "Board Geometry/Soldermask Top")
		(3 "B.Mask" user "Board Geometry/Soldermask Bottom")
		(17 "Dwgs.User" user "User.Drawings")
		(19 "Cmts.User" user "User.Comments")
		(21 "Eco1.User" user "User.Eco1")
		(23 "Eco2.User" user "User.Eco2")
		(25 "Edge.Cuts" user "Board Geometry/Outline")
		(27 "Margin" user)
		(31 "F.CrtYd" user "Package Geometry/Place Bound Top")
		(29 "B.CrtYd" user "Package Geometry/Place Bound Bottom")
		(35 "F.Fab" user "Ref Des/Assembly Top")
		(33 "B.Fab" user "Ref Des/Assembly Bottom")
	)
	(footprint ""
		(layer "F.Cu")
		(at 178.943 -140.172948 90)
		(property "Reference" "R19"
			(at 0 0 90)
			(layer "F.SilkS")
			(hide yes)
			(effects
				(font
					(size 1.27 1.27)
				)
			)
		)
		(property "Value" ""
			(at 0 0 90)
			(layer "F.Fab")
			(effects
				(font
					(size 1.27 1.27)
				)
			)
		)
		(duplicate_pad_numbers_are_jumpers no)
		(fp_line
			(start 0.7874 -0.4064)
			(end 0.7874 0.4064)
			(stroke
				(width 0.1524)
				(type default)
			)
			(layer "F.SilkS")
		)
		(fp_line
			(start -0.7874 -0.4064)
			(end 0.7874 -0.4064)
			(stroke
				(width 0.1524)
				(type default)
			)
			(layer "F.SilkS")
		)
		(fp_line
			(start 0.7874 0.4064)
			(end -0.7874 0.4064)
			(stroke
				(width 0.1524)
				(type default)
			)
			(layer "F.SilkS")
		)
		(fp_line
			(start -0.7874 0.4064)
			(end -0.7874 -0.4064)
			(stroke
				(width 0.1524)
				(type default)
			)
			(layer "F.SilkS")
		)
		(fp_line
			(start -0.12065 -0.305054)
			(end -0.12065 -0.2794)
			(stroke
				(width 0.1)
				(type default)
			)
			(layer "F.Fab")
		)
		(fp_line
			(start -0.67945 -0.305054)
			(end -0.12065 -0.305054)
			(stroke
				(width 0.1)
				(type default)
			)
			(layer "F.Fab")
		)
		(fp_line
			(start 0.67945 -0.3048)
			(end 0.67945 0.3048)
			(stroke
				(width 0.1)
				(type default)
			)
			(layer "F.Fab")
		)
		(fp_line
			(start 0.12065 -0.3048)
			(end 0.67945 -0.3048)
			(stroke
				(width 0.1)
				(type default)
			)
			(layer "F.Fab")
		)
		(fp_line
			(start 0.12065 -0.2794)
			(end 0.12065 -0.3048)
			(stroke
				(width 0.1)
				(type default)
			)
			(layer "F.Fab")
		)
		(fp_line
			(start -0.12065 -0.2794)
			(end 0.12065 -0.2794)
			(stroke
				(width 0.1)
				(type default)
			)
			(layer "F.Fab")
		)
		(fp_line
			(start 0.120396 0.2794)
			(end -0.12065 0.2794)
			(stroke
				(width 0.1)
				(type default)
			)
			(layer "F.Fab")
		)
		(fp_line
			(start -0.12065 0.2794)
			(end -0.12065 0.3048)
			(stroke
				(width 0.1)
				(type default)
			)
			(layer "F.Fab")
		)
		(fp_line
			(start 0.67945 0.3048)
			(end 0.120396 0.3048)
			(stroke
				(width 0.1)
				(type default)
			)
			(layer "F.Fab")
		)
		(fp_line
			(start 0.120396 0.3048)
			(end 0.120396 0.2794)
			(stroke
				(width 0.1)
				(type default)
			)
			(layer "F.Fab")
		)
		(fp_line
			(start -0.12065 0.3048)
			(end -0.67945 0.3048)
			(stroke
				(width 0.1)
				(type default)
			)
			(layer "F.Fab")
		)
		(fp_line
			(start -0.67945 0.3048)
			(end -0.67945 -0.305054)
			(stroke
				(width 0.1)
				(type default)
			)
			(layer "F.Fab")
		)
		(pad "1" smd circle
			(at -0.40005 0 90)
			(size 0 0)
			(layers "F.Cu" "F.Mask" "F.Paste")
			(net "RST_CPU1_PERST1_N")
		)
		(pad "2" smd circle
			(at 0.40005 0 90)
			(size 0 0)
			(layers "F.Cu" "F.Mask" "F.Paste")
			(net "GND")
		)
	)
	(footprint ""
		(layer "F.Cu")
		(at 243.74475 -50.335434)
		(property "Reference" "R1292"
			(at 0 0 0)
			(layer "F.SilkS")
			(hide yes)
			(effects
				(font
					(size 1.27 1.27)
				)
			)
		)
		(property "Value" ""
			(at 0 0 0)
			(layer "F.Fab")
			(effects
				(font
					(size 1.27 1.27)
				)
			)
		)
		(duplicate_pad_numbers_are_jumpers no)
		(fp_line
			(start -0.7874 -0.4064)
			(end 0.7874 -0.4064)
			(stroke
				(width 0.1524)
				(type default)
			)
			(layer "F.SilkS")
		)
		(fp_line
			(start -0.7874 0.4064)
			(end -0.7874 -0.4064)
			(stroke
				(width 0.1524)
				(type default)
			)
			(layer "F.SilkS")
		)
		(fp_line
			(start 0.7874 -0.4064)
			(end 0.7874 0.4064)
			(stroke
				(width 0.1524)
				(type default)
			)
			(layer "F.SilkS")
		)
		(fp_line
			(start 0.7874 0.4064)
			(end -0.7874 0.4064)
			(stroke
				(width 0.1524)
				(type default)
			)
			(layer "F.SilkS")
		)
		(fp_line
			(start -0.67945 -0.305054)
			(end -0.12065 -0.305054)
			(stroke
				(width 0.1)
				(type default)
			)
			(layer "F.Fab")
		)
		(fp_line
			(start -0.67945 0.3048)
			(end -0.67945 -0.305054)
			(stroke
				(width 0.1)
				(type default)
			)
			(layer "F.Fab")
		)
		(fp_line
			(start -0.12065 -0.305054)
			(end -0.12065 -0.2794)
			(stroke
				(width 0.1)
				(type default)
			)
			(layer "F.Fab")
		)
		(fp_line
			(start -0.12065 -0.2794)
			(end 0.12065 -0.2794)
			(stroke
				(width 0.1)
				(type default)
			)
			(layer "F.Fab")
		)
		(fp_line
			(start -0.12065 0.2794)
			(end -0.12065 0.3048)
			(stroke
				(width 0.1)
				(type default)
			)
			(layer "F.Fab")
		)
		(fp_line
			(start -0.12065 0.3048)
			(end -0.67945 0.3048)
			(stroke
				(width 0.1)
				(type default)
			)
			(layer "F.Fab")
		)
		(fp_line
			(start 0.120396 0.2794)
			(end -0.12065 0.2794)
			(stroke
				(width 0.1)
				(type default)
			)
			(layer "F.Fab")
		)
		(fp_line
			(start 0.120396 0.3048)
			(end 0.120396 0.2794)
			(stroke
				(width 0.1)
				(type default)
			)
			(layer "F.Fab")
		)
		(fp_line
			(start 0.12065 -0.3048)
			(end 0.67945 -0.3048)
			(stroke
				(width 0.1)
				(type default)
			)
			(layer "F.Fab")
		)
		(fp_line
			(start 0.12065 -0.2794)
			(end 0.12065 -0.3048)
			(stroke
				(width 0.1)
				(type default)
			)
			(layer "F.Fab")
		)
		(fp_line
			(start 0.67945 -0.3048)
			(end 0.67945 0.3048)
			(stroke
				(width 0.1)
				(type default)
			)
			(layer "F.Fab")
		)
		(fp_line
			(start 0.67945 0.3048)
			(end 0.120396 0.3048)
			(stroke
				(width 0.1)
				(type default)
			)
			(layer "F.Fab")
		)
		(pad "1" smd circle
			(at -0.40005 0)
			(size 0 0)
			(layers "F.Cu" "F.Mask" "F.Paste")
			(net "P12V_E1S_0_R")
		)
		(pad "2" smd circle
			(at 0.40005 0)
			(size 0 0)
			(layers "F.Cu" "F.Mask" "F.Paste")
			(net "VSENSE_P12V_INA230_8_INN")
		)
	)
)
